(kicad_pcb
	(version 20260206)
	(generator "pcbnew")
	(generator_version "10.0")
	(general
		(thickness 1.6)
		(legacy_teardrops no)
	)
	(paper "A4")
	(title_block
		(title "04192023_DAF0TMB3IC0_F0TG_MB_C_brd_V02_OCP.brd")
		(comment 1 "Grand Teton / footprints 3193-3197 of 8354")
	)
	(layers
		(0 "F.Cu" signal "TOP")
		(4 "In1.Cu" signal "GND")
		(6 "In2.Cu" signal "IN1")
		(8 "In3.Cu" signal "GND1")
		(10 "In4.Cu" signal "IN2")
		(12 "In5.Cu" signal "GND2")
		(14 "In6.Cu" signal "IN3")
		(16 "In7.Cu" signal "GND3")
		(18 "In8.Cu" signal "VCC")
		(20 "In9.Cu" signal "VCC1")
		(22 "In10.Cu" signal "GND4")
		(24 "In11.Cu" signal "IN4")
		(26 "In12.Cu" signal "GND5")
		(28 "In13.Cu" signal "IN5")
		(30 "In14.Cu" signal "GND6")
		(32 "In15.Cu" signal "IN6")
		(34 "In16.Cu" signal "GND7")
		(2 "B.Cu" signal "BOTTOM")
		(9 "F.Adhes" user "F.Adhesive")
		(11 "B.Adhes" user "B.Adhesive")
		(13 "F.Paste" user "Package Geometry/Pastemask Top")
		(15 "B.Paste" user "Package Geometry/Pastemask Bottom")
		(5 "F.SilkS" user "Ref Des/Silkscreen Top")
		(7 "B.SilkS" user "Ref Des/Silkscreen Bottom")
		(1 "F.Mask" user "Board Geometry/Soldermask Top")
		(3 "B.Mask" user "Board Geometry/Soldermask Bottom")
		(17 "Dwgs.User" user "User.Drawings")
		(19 "Cmts.User" user "User.Comments")
		(21 "Eco1.User" user "User.Eco1")
		(23 "Eco2.User" user "User.Eco2")
		(25 "Edge.Cuts" user "Board Geometry/Outline")
		(27 "Margin" user)
		(31 "F.CrtYd" user "Package Geometry/Place Bound Top")
		(29 "B.CrtYd" user "Package Geometry/Place Bound Bottom")
		(35 "F.Fab" user "Ref Des/Assembly Top")
		(33 "B.Fab" user "Ref Des/Assembly Bottom")
	)
	(footprint ""
		(layer "F.Cu")
		(at 307.470302 -427.141386 -90)
		(property "Reference" "Q133"
			(at 1.452372 -1.958848 90)
			(unlocked yes)
			(layer "F.SilkS")
			(effects
				(font
					(size 0.7874 0.5842)
					(thickness 0.1524)
				)
				(justify left)
			)
		)
		(property "Value" ""
			(at 0 0 270)
			(layer "F.Fab")
			(effects
				(font
					(size 1.27 1.27)
				)
			)
		)
		(duplicate_pad_numbers_are_jumpers no)
		(fp_line
			(start -1.332738 1.100074)
			(end -1.332738 -1.100074)
			(stroke
				(width 0.1524)
				(type default)
			)
			(layer "F.SilkS")
		)
		(fp_line
			(start 1.332738 1.100074)
			(end -1.332738 1.100074)
			(stroke
				(width 0.1524)
				(type default)
			)
			(layer "F.SilkS")
		)
		(fp_line
			(start 0 -0.541274)
			(end 0.4826 -1.100074)
			(stroke
				(width 0.1524)
				(type default)
			)
			(layer "F.SilkS")
		)
		(fp_line
			(start -1.332738 -1.100074)
			(end -0.4826 -1.100074)
			(stroke
				(width 0.1524)
				(type default)
			)
			(layer "F.SilkS")
		)
		(fp_line
			(start -0.4826 -1.100074)
			(end 0 -0.541274)
			(stroke
				(width 0.1524)
				(type default)
			)
			(layer "F.SilkS")
		)
		(fp_line
			(start 0.4826 -1.100074)
			(end 1.332738 -1.100074)
			(stroke
				(width 0.1524)
				(type default)
			)
			(layer "F.SilkS")
		)
		(fp_line
			(start 1.332738 -1.100074)
			(end 1.332738 1.100074)
			(stroke
				(width 0.1524)
				(type default)
			)
			(layer "F.SilkS")
		)
		(fp_poly
			(pts
				(xy -1.532636 -1.148334) (xy -2.277364 -1.396492) (xy -1.780794 -1.893062)
			)
			(stroke
				(width 0)
				(type default)
			)
			(fill yes)
			(layer "F.SilkS")
		)
		(fp_line
			(start -0.674878 1.100074)
			(end -0.674878 -1.100074)
			(stroke
				(width 0.1)
				(type default)
			)
			(layer "F.Fab")
		)
		(fp_line
			(start 0.674878 1.100074)
			(end -0.674878 1.100074)
			(stroke
				(width 0.1)
				(type default)
			)
			(layer "F.Fab")
		)
		(fp_line
			(start -0.674878 -1.100074)
			(end 0.674878 -1.100074)
			(stroke
				(width 0.1)
				(type default)
			)
			(layer "F.Fab")
		)
		(fp_line
			(start 0.674878 -1.100074)
			(end 0.674878 1.100074)
			(stroke
				(width 0.1)
				(type default)
			)
			(layer "F.Fab")
		)
		(fp_poly
			(pts
				(xy -2.2352 -0.298958) (xy -2.2352 -1.001014) (xy -1.533144 -0.649986)
			)
			(stroke
				(width 0)
				(type default)
			)
			(fill yes)
			(layer "F.Fab")
		)
		(pad "1" smd rect
			(at -0.94996 -0.649986)
			(size 0.4318 0.508)
			(layers "F.Cu" "F.Mask" "F.Paste")
			(net "GND")
		)
		(pad "2" smd rect
			(at -0.94996 0)
			(size 0.4318 0.508)
			(layers "F.Cu" "F.Mask" "F.Paste")
			(net "PRSNT_CABLE_GPU_A2_N")
		)
		(pad "3" smd rect
			(at -0.94996 0.649986)
			(size 0.4318 0.508)
			(layers "F.Cu" "F.Mask" "F.Paste")
			(net "PRSNT_CABLE_GPU_A2_ISO_N")
		)
		(pad "4" smd rect
			(at 0.94996 0.649986)
			(size 0.4318 0.508)
			(layers "F.Cu" "F.Mask" "F.Paste")
			(net "GND")
		)
		(pad "5" smd rect
			(at 0.94996 0)
			(size 0.4318 0.508)
			(layers "F.Cu" "F.Mask" "F.Paste")
			(net "PRSNT_CABLE_GPU_A2")
		)
		(pad "6" smd rect
			(at 0.94996 -0.649986)
			(size 0.4318 0.508)
			(layers "F.Cu" "F.Mask" "F.Paste")
			(net "PRSNT_CABLE_GPU_A2")
		)
	)
	(footprint ""
		(layer "F.Cu")
		(at 490.57433 7.610602 -90)
		(property "Reference" "X8004"
			(at -1.859788 4.892802 0)
			(unlocked yes)
			(layer "F.SilkS")
			(effects
				(font
					(size 0.7874 0.5842)
					(thickness 0.1524)
				)
				(justify left)
			)
		)
		(property "Value" ""
			(at 0 0 270)
			(layer "F.Fab")
			(effects
				(font
					(size 1.27 1.27)
				)
			)
		)
		(property "Device Type" "TP_TDR_4P_FTS_TH-TP_TDR_4P_DIP,EMPTY,TP15"
			(at 1.30175 1.27 0)
			(unlocked yes)
			(layer "F.Fab")
			(hide yes)
			(effects
				(font
					(size 0.635 0.4064)
					(thickness 0.1524)
				)
			)
		)
		(property "User Part Number" "N_A"
			(at 1.30175 1.27 0)
			(unlocked yes)
			(layer "Cmts.User")
			(hide yes)
			(effects
				(font
					(size 0.635 0.4064)
					(thickness 0.1524)
				)
			)
		)
		(duplicate_pad_numbers_are_jumpers no)
		(fp_line
			(start 0 3.81)
			(end 2.54 3.81)
			(stroke
				(width 0.1524)
				(type default)
			)
			(layer "F.SilkS")
		)
		(fp_line
			(start 2.54 3.81)
			(end 2.54 3.6703)
			(stroke
				(width 0.1524)
				(type default)
			)
			(layer "F.SilkS")
		)
		(fp_line
			(start 0 3.175)
			(end 0 3.81)
			(stroke
				(width 0.1524)
				(type default)
			)
			(layer "F.SilkS")
		)
		(fp_line
			(start 2.54 1.4097)
			(end 2.54 1.1303)
			(stroke
				(width 0.1524)
				(type default)
			)
			(layer "F.SilkS")
		)
		(fp_line
			(start 0 0.635)
			(end 0 1.905)
			(stroke
				(width 0.1524)
				(type default)
			)
			(layer "F.SilkS")
		)
		(fp_line
			(start 2.54 -1.1303)
			(end 2.54 -1.27)
			(stroke
				(width 0.1524)
				(type default)
			)
			(layer "F.SilkS")
		)
		(fp_line
			(start 0 -1.27)
			(end 0 -0.635)
			(stroke
				(width 0.1524)
				(type default)
			)
			(layer "F.SilkS")
		)
		(fp_line
			(start 2.54 -1.27)
			(end 0 -1.27)
			(stroke
				(width 0.1524)
				(type default)
			)
			(layer "F.SilkS")
		)
		(fp_poly
			(pts
				(xy -2.285746 -0.762) (xy -0.761746 0) (xy -2.285746 0.762)
			)
			(stroke
				(width 0)
				(type default)
			)
			(fill yes)
			(layer "F.SilkS")
		)
		(fp_line
			(start 0 3.81)
			(end 2.54 3.81)
			(stroke
				(width 0.1)
				(type default)
			)
			(layer "F.Fab")
		)
		(fp_line
			(start 2.54 3.81)
			(end 2.54 -1.27)
			(stroke
				(width 0.1)
				(type default)
			)
			(layer "F.Fab")
		)
		(fp_line
			(start 0 -1.27)
			(end 0 3.81)
			(stroke
				(width 0.1)
				(type default)
			)
			(layer "F.Fab")
		)
		(fp_line
			(start 2.54 -1.27)
			(end 0 -1.27)
			(stroke
				(width 0.1)
				(type default)
			)
			(layer "F.Fab")
		)
		(fp_poly
			(pts
				(xy -0.761746 0) (xy -2.285746 -0.762) (xy -2.285746 0.762)
			)
			(stroke
				(width 0)
				(type default)
			)
			(fill yes)
			(layer "F.Fab")
		)
		(pad "1" thru_hole circle
			(at 0 0 270)
			(size 1.0033 1.0033)
			(drill 0.249936)
			(layers "*.Cu" "*.Mask")
			(remove_unused_layers no)
			(net "TDR_DIFF_85_IN3_DP")
			(clearance 0.10795)
			(thermal_gap 0.10795)
			(padstack
				(mode front_inner_back)
				(layer "Inner"
					(shape circle)
					(size 0.8001 0.8001)
					(clearance 0.1524)
				)
				(layer "B.Cu"
					(shape circle)
					(size 1.0033 1.0033)
					(clearance 0.10795)
				)
			)
		)
		(pad "2" thru_hole circle
			(at 2.54 0 270)
			(size 1.9939 1.9939)
			(drill 0.249936)
			(layers "*.Cu" "*.Mask")
			(remove_unused_layers no)
			(net "T1_GND")
			(clearance 0.10795)
			(thermal_gap 0.10795)
			(padstack
				(mode front_inner_back)
				(layer "Inner"
					(shape circle)
					(size 0.8001 0.8001)
					(clearance 0.1524)
				)
				(layer "B.Cu"
					(shape circle)
					(size 1.9939 1.9939)
					(clearance 0.10795)
				)
			)
		)
		(pad "3" thru_hole circle
			(at 2.54 2.54 270)
			(size 1.9939 1.9939)
			(drill 0.249936)
			(layers "*.Cu" "*.Mask")
			(remove_unused_layers no)
			(net "T1_GND")
			(clearance 0.10795)
			(thermal_gap 0.10795)
			(padstack
				(mode front_inner_back)
				(layer "Inner"
					(shape circle)
					(size 0.8001 0.8001)
					(clearance 0.1524)
				)
				(layer "B.Cu"
					(shape circle)
					(size 1.9939 1.9939)
					(clearance 0.10795)
				)
			)
		)
		(pad "4" thru_hole circle
			(at 0 2.54 270)
			(size 1.0033 1.0033)
			(drill 0.249936)
			(layers "*.Cu" "*.Mask")
			(remove_unused_layers no)
			(net "TDR_DIFF_85_IN3_DN")
			(clearance 0.10795)
			(thermal_gap 0.10795)
			(padstack
				(mode front_inner_back)
				(layer "Inner"
					(shape circle)
					(size 0.8001 0.8001)
					(clearance 0.1524)
				)
				(layer "B.Cu"
					(shape circle)
					(size 1.0033 1.0033)
					(clearance 0.10795)
				)
			)
		)
	)
	(footprint ""
		(layer "F.Cu")
		(at 253.506224 -132.337556 180)
		(property "Reference" "R602"
			(at 0 0 180)
			(layer "F.SilkS")
			(hide yes)
			(effects
				(font
					(size 1.27 1.27)
				)
			)
		)
		(property "Value" ""
			(at 0 0 180)
			(layer "F.Fab")
			(effects
				(font
					(size 1.27 1.27)
				)
			)
		)
		(duplicate_pad_numbers_are_jumpers no)
		(fp_line
			(start 0.7874 0.4064)
			(end -0.7874 0.4064)
			(stroke
				(width 0.1524)
				(type default)
			)
			(layer "F.SilkS")
		)
		(fp_line
			(start 0.7874 -0.4064)
			(end 0.7874 0.4064)
			(stroke
				(width 0.1524)
				(type default)
			)
			(layer "F.SilkS")
		)
		(fp_line
			(start -0.7874 0.4064)
			(end -0.7874 -0.4064)
			(stroke
				(width 0.1524)
				(type default)
			)
			(layer "F.SilkS")
		)
		(fp_line
			(start -0.7874 -0.4064)
			(end 0.7874 -0.4064)
			(stroke
				(width 0.1524)
				(type default)
			)
			(layer "F.SilkS")
		)
		(fp_line
			(start 0.67945 0.3048)
			(end 0.120396 0.3048)
			(stroke
				(width 0.1)
				(type default)
			)
			(layer "F.Fab")
		)
		(fp_line
			(start 0.67945 -0.3048)
			(end 0.67945 0.3048)
			(stroke
				(width 0.1)
				(type default)
			)
			(layer "F.Fab")
		)
		(fp_line
			(start 0.12065 -0.2794)
			(end 0.12065 -0.3048)
			(stroke
				(width 0.1)
				(type default)
			)
			(layer "F.Fab")
		)
		(fp_line
			(start 0.12065 -0.3048)
			(end 0.67945 -0.3048)
			(stroke
				(width 0.1)
				(type default)
			)
			(layer "F.Fab")
		)
		(fp_line
			(start 0.120396 0.3048)
			(end 0.120396 0.2794)
			(stroke
				(width 0.1)
				(type default)
			)
			(layer "F.Fab")
		)
		(fp_line
			(start 0.120396 0.2794)
			(end -0.12065 0.2794)
			(stroke
				(width 0.1)
				(type default)
			)
			(layer "F.Fab")
		)
		(fp_line
			(start -0.12065 0.3048)
			(end -0.67945 0.3048)
			(stroke
				(width 0.1)
				(type default)
			)
			(layer "F.Fab")
		)
		(fp_line
			(start -0.12065 0.2794)
			(end -0.12065 0.3048)
			(stroke
				(width 0.1)
				(type default)
			)
			(layer "F.Fab")
		)
		(fp_line
			(start -0.12065 -0.2794)
			(end 0.12065 -0.2794)
			(stroke
				(width 0.1)
				(type default)
			)
			(layer "F.Fab")
		)
		(fp_line
			(start -0.12065 -0.305054)
			(end -0.12065 -0.2794)
			(stroke
				(width 0.1)
				(type default)
			)
			(layer "F.Fab")
		)
		(fp_line
			(start -0.67945 0.3048)
			(end -0.67945 -0.305054)
			(stroke
				(width 0.1)
				(type default)
			)
			(layer "F.Fab")
		)
		(fp_line
			(start -0.67945 -0.305054)
			(end -0.12065 -0.305054)
			(stroke
				(width 0.1)
				(type default)
			)
			(layer "F.Fab")
		)
		(pad "1" smd circle
			(at -0.40005 0 180)
			(size 0 0)
			(layers "F.Cu" "F.Mask" "F.Paste")
			(net "SPI_CPU0_LVC3_CLK")
		)
		(pad "2" smd circle
			(at 0.40005 0 180)
			(size 0 0)
			(layers "F.Cu" "F.Mask" "F.Paste")
			(net "SPI_CPU0_LVC3_SCM_CLK")
		)
	)
	(footprint ""
		(layer "F.Cu")
		(at 167.090344 -344.153998 -90)
		(property "Reference" "PR409"
			(at 0 0 270)
			(layer "F.SilkS")
			(hide yes)
			(effects
				(font
					(size 1.27 1.27)
				)
			)
		)
		(property "Value" ""
			(at 0 0 270)
			(layer "F.Fab")
			(effects
				(font
					(size 1.27 1.27)
				)
			)
		)
		(duplicate_pad_numbers_are_jumpers no)
		(fp_line
			(start -0.7874 0.4064)
			(end -0.7874 -0.4064)
			(stroke
				(width 0.1524)
				(type default)
			)
			(layer "F.SilkS")
		)
		(fp_line
			(start 0.7874 0.4064)
			(end -0.7874 0.4064)
			(stroke
				(width 0.1524)
				(type default)
			)
			(layer "F.SilkS")
		)
		(fp_line
			(start -0.7874 -0.4064)
			(end 0.7874 -0.4064)
			(stroke
				(width 0.1524)
				(type default)
			)
			(layer "F.SilkS")
		)
		(fp_line
			(start 0.7874 -0.4064)
			(end 0.7874 0.4064)
			(stroke
				(width 0.1524)
				(type default)
			)
			(layer "F.SilkS")
		)
		(fp_line
			(start -0.67945 0.3048)
			(end -0.67945 -0.305054)
			(stroke
				(width 0.1)
				(type default)
			)
			(layer "F.Fab")
		)
		(fp_line
			(start -0.12065 0.3048)
			(end -0.67945 0.3048)
			(stroke
				(width 0.1)
				(type default)
			)
			(layer "F.Fab")
		)
		(fp_line
			(start 0.120396 0.3048)
			(end 0.120396 0.2794)
			(stroke
				(width 0.1)
				(type default)
			)
			(layer "F.Fab")
		)
		(fp_line
			(start 0.67945 0.3048)
			(end 0.120396 0.3048)
			(stroke
				(width 0.1)
				(type default)
			)
			(layer "F.Fab")
		)
		(fp_line
			(start -0.12065 0.2794)
			(end -0.12065 0.3048)
			(stroke
				(width 0.1)
				(type default)
			)
			(layer "F.Fab")
		)
		(fp_line
			(start 0.120396 0.2794)
			(end -0.12065 0.2794)
			(stroke
				(width 0.1)
				(type default)
			)
			(layer "F.Fab")
		)
		(fp_line
			(start -0.12065 -0.2794)
			(end 0.12065 -0.2794)
			(stroke
				(width 0.1)
				(type default)
			)
			(layer "F.Fab")
		)
		(fp_line
			(start 0.12065 -0.2794)
			(end 0.12065 -0.3048)
			(stroke
				(width 0.1)
				(type default)
			)
			(layer "F.Fab")
		)
		(fp_line
			(start 0.12065 -0.3048)
			(end 0.67945 -0.3048)
			(stroke
				(width 0.1)
				(type default)
			)
			(layer "F.Fab")
		)
		(fp_line
			(start 0.67945 -0.3048)
			(end 0.67945 0.3048)
			(stroke
				(width 0.1)
				(type default)
			)
			(layer "F.Fab")
		)
		(fp_line
			(start -0.67945 -0.305054)
			(end -0.12065 -0.305054)
			(stroke
				(width 0.1)
				(type default)
			)
			(layer "F.Fab")
		)
		(fp_line
			(start -0.12065 -0.305054)
			(end -0.12065 -0.2794)
			(stroke
				(width 0.1)
				(type default)
			)
			(layer "F.Fab")
		)
		(pad "1" smd circle
			(at -0.40005 0 270)
			(size 0 0)
			(layers "F.Cu" "F.Mask" "F.Paste")
			(net "NC_PVDD11_S3_P1_IMON8")
		)
		(pad "2" smd circle
			(at 0.40005 0 270)
			(size 0 0)
			(layers "F.Cu" "F.Mask" "F.Paste")
			(net "GND")
		)
	)
	(footprint ""
		(layer "F.Cu")
		(at 107.363768 -340.08949 -90)
		(property "Reference" "PC140_6"
			(at 0 0 270)
			(layer "F.SilkS")
			(hide yes)
			(effects
				(font
					(size 1.27 1.27)
				)
			)
		)
		(property "Value" ""
			(at 0 0 270)
			(layer "F.Fab")
			(effects
				(font
					(size 1.27 1.27)
				)
			)
		)
		(duplicate_pad_numbers_are_jumpers no)
		(fp_line
			(start -0.7874 0.4064)
			(end -0.7874 -0.4064)
			(stroke
				(width 0.1524)
				(type default)
			)
			(layer "F.SilkS")
		)
		(fp_line
			(start 0.7874 0.4064)
			(end -0.7874 0.4064)
			(stroke
				(width 0.1524)
				(type default)
			)
			(layer "F.SilkS")
		)
		(fp_line
			(start -0.7874 -0.4064)
			(end 0.7874 -0.4064)
			(stroke
				(width 0.1524)
				(type default)
			)
			(layer "F.SilkS")
		)
		(fp_line
			(start 0.7874 -0.4064)
			(end 0.7874 0.4064)
			(stroke
				(width 0.1524)
				(type default)
			)
			(layer "F.SilkS")
		)
		(fp_line
			(start -0.67945 0.3048)
			(end -0.67945 -0.305054)
			(stroke
				(width 0.1)
				(type default)
			)
			(layer "F.Fab")
		)
		(fp_line
			(start -0.12065 0.3048)
			(end -0.67945 0.3048)
			(stroke
				(width 0.1)
				(type default)
			)
			(layer "F.Fab")
		)
		(fp_line
			(start 0.120396 0.3048)
			(end 0.120396 0.2794)
			(stroke
				(width 0.1)
				(type default)
			)
			(layer "F.Fab")
		)
		(fp_line
			(start 0.67945 0.3048)
			(end 0.120396 0.3048)
			(stroke
				(width 0.1)
				(type default)
			)
			(layer "F.Fab")
		)
		(fp_line
			(start -0.12065 0.2794)
			(end -0.12065 0.3048)
			(stroke
				(width 0.1)
				(type default)
			)
			(layer "F.Fab")
		)
		(fp_line
			(start 0.120396 0.2794)
			(end -0.12065 0.2794)
			(stroke
				(width 0.1)
				(type default)
			)
			(layer "F.Fab")
		)
		(fp_line
			(start -0.12065 -0.2794)
			(end 0.12065 -0.2794)
			(stroke
				(width 0.1)
				(type default)
			)
			(layer "F.Fab")
		)
		(fp_line
			(start 0.12065 -0.2794)
			(end 0.12065 -0.3048)
			(stroke
				(width 0.1)
				(type default)
			)
			(layer "F.Fab")
		)
		(fp_line
			(start 0.12065 -0.3048)
			(end 0.67945 -0.3048)
			(stroke
				(width 0.1)
				(type default)
			)
			(layer "F.Fab")
		)
		(fp_line
			(start 0.67945 -0.3048)
			(end 0.67945 0.3048)
			(stroke
				(width 0.1)
				(type default)
			)
			(layer "F.Fab")
		)
		(fp_line
			(start -0.67945 -0.305054)
			(end -0.12065 -0.305054)
			(stroke
				(width 0.1)
				(type default)
			)
			(layer "F.Fab")
		)
		(fp_line
			(start -0.12065 -0.305054)
			(end -0.12065 -0.2794)
			(stroke
				(width 0.1)
				(type default)
			)
			(layer "F.Fab")
		)
		(pad "1" smd circle
			(at -0.40005 0 270)
			(size 0 0)
			(layers "F.Cu" "F.Mask" "F.Paste")
			(net "SW_P12V_AUX_PVDDCR_CPU1_P1_FLT")
		)
		(pad "2" smd circle
			(at 0.40005 0 270)
			(size 0 0)
			(layers "F.Cu" "F.Mask" "F.Paste")
			(net "GND")
		)
	)
)
